# TIMECARD (Time Appliance Project (Time Card)) — schematic netlist excerpt (pin names and nets, part order shuffled) for the footprints in the layout excerpt that follows; sources: Cadence DE-HDL packaged netlist, KiCad conversion of R4006-B0001-02_R01.brd

C299  CAPACITOR  10UF 25V 20%  pkg SMC_0805R_H057  page 27 : \1\ = XP12R0V_IN ; \2\ = SG
R261  RESISTOR  330OHM 1%  pkg SMC_0402R_H016  page 26 : \1\ = UNNAMED_14_OPTICAL_I137_A ; \2\ = XP3R3V_FPGA

(kicad_pcb
	(version 20260206)
	(generator "pcbnew")
	(generator_version "10.0")
	(general
		(thickness 1.6)
		(legacy_teardrops no)
	)
	(paper "A4")
	(title_block
		(title "timecard-production-celestica-r4006 — R4006-B0001-02_R01.brd")
		(comment 1 "Time Appliance Project (Time Card) / footprints 991-992 of 1113")
	)
	(layers
		(0 "F.Cu" signal "TOP")
		(4 "In1.Cu" signal "L02_GND1")
		(6 "In2.Cu" signal "L03_SIG1")
		(8 "In3.Cu" signal "L04_GND2")
		(10 "In4.Cu" signal "L05_VCC1")
		(12 "In5.Cu" signal "L06_VCC2")
		(14 "In6.Cu" signal "L07_GND3")
		(16 "In7.Cu" signal "L08_SIG2")
		(18 "In8.Cu" signal "L09_GND4")
		(2 "B.Cu" signal "BOTTOM")
		(9 "F.Adhes" user "F.Adhesive")
		(11 "B.Adhes" user "B.Adhesive")
		(13 "F.Paste" user "Package Geometry/Pastemask Top")
		(15 "B.Paste" user "Package Geometry/Pastemask Bottom")
		(5 "F.SilkS" user "Ref Des/Silkscreen Top")
		(7 "B.SilkS" user "Ref Des/Silkscreen Bottom")
		(1 "F.Mask" user "Board Geometry/Soldermask Top")
		(3 "B.Mask" user "Board Geometry/Soldermask Bottom")
		(17 "Dwgs.User" user "User.Drawings")
		(19 "Cmts.User" user "User.Comments")
		(21 "Eco1.User" user "User.Eco1")
		(23 "Eco2.User" user "User.Eco2")
		(25 "Edge.Cuts" user "Board Geometry/Outline")
		(27 "Margin" user)
		(31 "F.CrtYd" user "Package Geometry/Place Bound Top")
		(29 "B.CrtYd" user "Package Geometry/Place Bound Bottom")
		(35 "F.Fab" user "Ref Des/Assembly Top")
		(33 "B.Fab" user "Ref Des/Assembly Bottom")
	)
	(footprint ""
		(layer "B.Cu")
		(at 139.6492 -83.5152)
		(property "Reference" "C299"
			(at 0.4318 -6.61543 0)
			(unlocked yes)
			(layer "B.SilkS")
			(effects
				(font
					(size 0.7874 0.5842)
					(thickness 0.1524)
				)
				(justify mirror)
			)
		)
		(property "Value" "VAL*"
			(at -0.0762 3.134106 0)
			(unlocked yes)
			(layer "B.Fab")
			(hide yes)
			(effects
				(font
					(size 0.7874 0.5842)
					(thickness 0.1524)
				)
				(justify mirror)
			)
		)
		(property "Device Type" "CAPACITOR-G107-0F106-EM,10UF,2A"
			(at -0.0508 2.194306 0)
			(unlocked yes)
			(layer "B.Fab")
			(hide yes)
			(effects
				(font
					(size 0.7874 0.5842)
					(thickness 0.1524)
				)
				(justify mirror)
			)
		)
		(property "User Part Number" "PARTNUM*"
			(at -0.1016 5.013706 0)
			(unlocked yes)
			(layer "Cmts.User")
			(hide yes)
			(effects
				(font
					(size 0.7874 0.5842)
					(thickness 0.1524)
				)
				(justify mirror)
			)
		)
		(property "Tolerance" "TOL*"
			(at -0.0762 4.048506 0)
			(unlocked yes)
			(layer "Cmts.User")
			(hide yes)
			(effects
				(font
					(size 0.7874 0.5842)
					(thickness 0.1524)
				)
				(justify mirror)
			)
		)
		(duplicate_pad_numbers_are_jumpers no)
		(fp_line
			(start -1.5748 -0.9398)
			(end 1.5748 -0.9398)
			(stroke
				(width 0.1)
				(type default)
			)
			(layer "B.SilkS")
		)
		(fp_line
			(start -1.5748 0.9398)
			(end -1.5748 -0.9398)
			(stroke
				(width 0.1)
				(type default)
			)
			(layer "B.SilkS")
		)
		(fp_line
			(start 1.5748 -0.9398)
			(end 1.5748 0.9398)
			(stroke
				(width 0.1)
				(type default)
			)
			(layer "B.SilkS")
		)
		(fp_line
			(start 1.5748 0.9398)
			(end -1.5748 0.9398)
			(stroke
				(width 0.1)
				(type default)
			)
			(layer "B.SilkS")
		)
		(fp_rect
			(start 1.5748 -0.9398)
			(end -1.5748 0.9398)
			(stroke
				(width 0)
				(type default)
			)
			(fill no)
			(layer "B.CrtYd")
		)
		(fp_line
			(start -1.016 -0.635)
			(end 1.016 -0.635)
			(stroke
				(width 0.1)
				(type default)
			)
			(layer "B.Fab")
		)
		(fp_line
			(start -1.016 0.635)
			(end -1.016 -0.635)
			(stroke
				(width 0.1)
				(type default)
			)
			(layer "B.Fab")
		)
		(fp_line
			(start 1.016 -0.635)
			(end 1.016 0.635)
			(stroke
				(width 0.1)
				(type default)
			)
			(layer "B.Fab")
		)
		(fp_line
			(start 1.016 0.635)
			(end -1.016 0.635)
			(stroke
				(width 0.1)
				(type default)
			)
			(layer "B.Fab")
		)
		(pad "1" smd rect
			(at 0.8382 0 180)
			(size 0.9652 1.3716)
			(layers "B.Cu" "B.Mask" "B.Paste")
			(net "XP12R0V_IN")
		)
		(pad "2" smd rect
			(at -0.8382 0 180)
			(size 0.9652 1.3716)
			(layers "B.Cu" "B.Mask" "B.Paste")
			(net "SG")
		)
		(zone
			(layer "B.Cu")
			(hatch none 0.5)
			(connect_pads
				(clearance 0)
			)
			(min_thickness 0.25)
			(keepout
				(tracks not_allowed)
				(vias allowed)
				(pads allowed)
				(copperpour not_allowed)
				(footprints allowed)
			)
			(placement
				(enabled no)
				(sheetname "")
			)
			(fill
				(thermal_gap 0.5)
				(thermal_bridge_width 0.5)
				(island_removal_mode 0)
			)
			(polygon
				(pts
					(xy 139.8778 -84.1502) (xy 139.4206 -84.1502) (xy 139.4206 -82.8802) (xy 139.8778 -82.8802)
				)
			)
		)
		(zone
			(layer "B.Cu")
			(hatch none 0.5)
			(connect_pads
				(clearance 0)
			)
			(min_thickness 0.25)
			(keepout
				(tracks allowed)
				(vias not_allowed)
				(pads allowed)
				(copperpour not_allowed)
				(footprints allowed)
			)
			(placement
				(enabled no)
				(sheetname "")
			)
			(fill
				(thermal_gap 0.5)
				(thermal_bridge_width 0.5)
				(island_removal_mode 0)
			)
			(polygon
				(pts
					(xy 139.8778 -84.1502) (xy 139.4206 -84.1502) (xy 139.4206 -82.8802) (xy 139.8778 -82.8802)
				)
			)
		)
	)
	(footprint ""
		(layer "B.Cu")
		(at 147.066 -107.696 90)
		(property "Reference" "R261"
			(at 0 1.99263 270)
			(unlocked yes)
			(layer "B.SilkS")
			(effects
				(font
					(size 0.7874 0.5842)
					(thickness 0.1524)
				)
				(justify mirror)
			)
		)
		(property "Value" "VAL*"
			(at -0.02032 2.13233 90)
			(unlocked yes)
			(layer "B.Fab")
			(hide yes)
			(effects
				(font
					(size 0.7874 0.5842)
					(thickness 0.1524)
				)
				(justify mirror)
			)
		)
		(property "Device Type" "RESISTOR-G155-13300-01,330OHM,A"
			(at -0.008382 1.210564 90)
			(unlocked yes)
			(layer "B.Fab")
			(hide yes)
			(effects
				(font
					(size 0.7874 0.5842)
					(thickness 0.1524)
				)
				(justify mirror)
			)
		)
		(property "User Part Number" "PARTNUM*"
			(at -0.02032 4.024884 90)
			(unlocked yes)
			(layer "Cmts.User")
			(hide yes)
			(effects
				(font
					(size 0.7874 0.5842)
					(thickness 0.1524)
				)
				(justify mirror)
			)
		)
		(property "Tolerance" "TOL*"
			(at -0.044704 3.05435 90)
			(unlocked yes)
			(layer "Cmts.User")
			(hide yes)
			(effects
				(font
					(size 0.7874 0.5842)
					(thickness 0.1524)
				)
				(justify mirror)
			)
		)
		(duplicate_pad_numbers_are_jumpers no)
		(fp_line
			(start 1.143 -0.5588)
			(end 1.143 0.5588)
			(stroke
				(width 0.1)
				(type default)
			)
			(layer "B.SilkS")
		)
		(fp_line
			(start -1.143 -0.5588)
			(end 1.143 -0.5588)
			(stroke
				(width 0.1)
				(type default)
			)
			(layer "B.SilkS")
		)
		(fp_line
			(start 1.143 0.5588)
			(end -1.143 0.5588)
			(stroke
				(width 0.1)
				(type default)
			)
			(layer "B.SilkS")
		)
		(fp_line
			(start -1.143 0.5588)
			(end -1.143 -0.5588)
			(stroke
				(width 0.1)
				(type default)
			)
			(layer "B.SilkS")
		)
		(fp_rect
			(start -1.143 -0.5588)
			(end 1.143 0.5588)
			(stroke
				(width 0)
				(type default)
			)
			(fill no)
			(layer "B.CrtYd")
		)
		(fp_line
			(start 0.508 -0.3048)
			(end 0.508 0.3048)
			(stroke
				(width 0.1)
				(type default)
			)
			(layer "B.Fab")
		)
		(fp_line
			(start -0.508 -0.3048)
			(end 0.508 -0.3048)
			(stroke
				(width 0.1)
				(type default)
			)
			(layer "B.Fab")
		)
		(fp_line
			(start 0.508 0.3048)
			(end -0.508 0.3048)
			(stroke
				(width 0.1)
				(type default)
			)
			(layer "B.Fab")
		)
		(fp_line
			(start -0.508 0.3048)
			(end -0.508 -0.3048)
			(stroke
				(width 0.1)
				(type default)
			)
			(layer "B.Fab")
		)
		(pad "1" smd rect
			(at 0.5334 0 270)
			(size 0.7112 0.6096)
			(layers "B.Cu" "B.Mask" "B.Paste")
			(net "UNNAMED_14_OPTICAL_I137_A")
		)
		(pad "2" smd rect
			(at -0.5334 0 270)
			(size 0.7112 0.6096)
			(layers "B.Cu" "B.Mask" "B.Paste")
			(net "XP3R3V_FPGA")
		)
		(zone
			(layer "B.Cu")
			(hatch none 0.5)
			(connect_pads
				(clearance 0)
			)
			(min_thickness 0.25)
			(keepout
				(tracks allowed)
				(vias not_allowed)
				(pads allowed)
				(copperpour not_allowed)
				(footprints allowed)
			)
			(placement
				(enabled no)
				(sheetname "")
			)
			(fill
				(thermal_gap 0.5)
				(thermal_bridge_width 0.5)
				(island_removal_mode 0)
			)
			(polygon
				(pts
					(xy 146.7612 -107.6198) (xy 147.3708 -107.6198) (xy 147.3708 -107.7722) (xy 146.7612 -107.7722)
				)
			)
		)
	)
)
